# T6G (Grand Teton) — schematic netlist excerpt (pin names and nets, part order shuffled) for the footprints in the layout excerpt that follows; sources: Cadence DE-HDL packaged netlist, KiCad conversion of 04192023_DAF0TMB3IC0_F0TG_MB_C_brd_V02_OCP.brd

R3563  Q_RES  0 5% CHIP  pkg 0402LF  page 236 : A = OCP_SFF_P3V3_ADC_ALERT_R ; B = OCP_SFF_P3V3_P12V_ADC_R_ALERT
PR442  Q_RES  0 5% CHIP  pkg 0402LF  page 201 : A = PVDDCR_CPU1_P0_PVCC ; B = P5V_AUX

(kicad_pcb
	(version 20260206)
	(generator "pcbnew")
	(generator_version "10.0")
	(general
		(thickness 1.6)
		(legacy_teardrops no)
	)
	(paper "A4")
	(title_block
		(title "04192023_DAF0TMB3IC0_F0TG_MB_C_brd_V02_OCP.brd")
		(comment 1 "Grand Teton / footprints 226-227 of 8354")
	)
	(layers
		(0 "F.Cu" signal "TOP")
		(4 "In1.Cu" signal "GND")
		(6 "In2.Cu" signal "IN1")
		(8 "In3.Cu" signal "GND1")
		(10 "In4.Cu" signal "IN2")
		(12 "In5.Cu" signal "GND2")
		(14 "In6.Cu" signal "IN3")
		(16 "In7.Cu" signal "GND3")
		(18 "In8.Cu" signal "VCC")
		(20 "In9.Cu" signal "VCC1")
		(22 "In10.Cu" signal "GND4")
		(24 "In11.Cu" signal "IN4")
		(26 "In12.Cu" signal "GND5")
		(28 "In13.Cu" signal "IN5")
		(30 "In14.Cu" signal "GND6")
		(32 "In15.Cu" signal "IN6")
		(34 "In16.Cu" signal "GND7")
		(2 "B.Cu" signal "BOTTOM")
		(9 "F.Adhes" user "F.Adhesive")
		(11 "B.Adhes" user "B.Adhesive")
		(13 "F.Paste" user "Package Geometry/Pastemask Top")
		(15 "B.Paste" user "Package Geometry/Pastemask Bottom")
		(5 "F.SilkS" user "Ref Des/Silkscreen Top")
		(7 "B.SilkS" user "Ref Des/Silkscreen Bottom")
		(1 "F.Mask" user "Board Geometry/Soldermask Top")
		(3 "B.Mask" user "Board Geometry/Soldermask Bottom")
		(17 "Dwgs.User" user "User.Drawings")
		(19 "Cmts.User" user "User.Comments")
		(21 "Eco1.User" user "User.Eco1")
		(23 "Eco2.User" user "User.Eco2")
		(25 "Edge.Cuts" user "Board Geometry/Outline")
		(27 "Margin" user)
		(31 "F.CrtYd" user "Package Geometry/Place Bound Top")
		(29 "B.CrtYd" user "Package Geometry/Place Bound Bottom")
		(35 "F.Fab" user "Ref Des/Assembly Top")
		(33 "B.Fab" user "Ref Des/Assembly Bottom")
	)
	(footprint ""
		(layer "F.Cu")
		(at 445.19088 -94.602808)
		(property "Reference" "R3563"
			(at 0 0 0)
			(layer "F.SilkS")
			(hide yes)
			(effects
				(font
					(size 1.27 1.27)
				)
			)
		)
		(property "Value" ""
			(at 0 0 0)
			(layer "F.Fab")
			(effects
				(font
					(size 1.27 1.27)
				)
			)
		)
		(duplicate_pad_numbers_are_jumpers no)
		(fp_line
			(start -0.7874 -0.4064)
			(end 0.7874 -0.4064)
			(stroke
				(width 0.1524)
				(type default)
			)
			(layer "F.SilkS")
		)
		(fp_line
			(start -0.7874 0.4064)
			(end -0.7874 -0.4064)
			(stroke
				(width 0.1524)
				(type default)
			)
			(layer "F.SilkS")
		)
		(fp_line
			(start 0.7874 -0.4064)
			(end 0.7874 0.4064)
			(stroke
				(width 0.1524)
				(type default)
			)
			(layer "F.SilkS")
		)
		(fp_line
			(start 0.7874 0.4064)
			(end -0.7874 0.4064)
			(stroke
				(width 0.1524)
				(type default)
			)
			(layer "F.SilkS")
		)
		(fp_line
			(start -0.67945 -0.305054)
			(end -0.12065 -0.305054)
			(stroke
				(width 0.1)
				(type default)
			)
			(layer "F.Fab")
		)
		(fp_line
			(start -0.67945 0.3048)
			(end -0.67945 -0.305054)
			(stroke
				(width 0.1)
				(type default)
			)
			(layer "F.Fab")
		)
		(fp_line
			(start -0.12065 -0.305054)
			(end -0.12065 -0.2794)
			(stroke
				(width 0.1)
				(type default)
			)
			(layer "F.Fab")
		)
		(fp_line
			(start -0.12065 -0.2794)
			(end 0.12065 -0.2794)
			(stroke
				(width 0.1)
				(type default)
			)
			(layer "F.Fab")
		)
		(fp_line
			(start -0.12065 0.2794)
			(end -0.12065 0.3048)
			(stroke
				(width 0.1)
				(type default)
			)
			(layer "F.Fab")
		)
		(fp_line
			(start -0.12065 0.3048)
			(end -0.67945 0.3048)
			(stroke
				(width 0.1)
				(type default)
			)
			(layer "F.Fab")
		)
		(fp_line
			(start 0.120396 0.2794)
			(end -0.12065 0.2794)
			(stroke
				(width 0.1)
				(type default)
			)
			(layer "F.Fab")
		)
		(fp_line
			(start 0.120396 0.3048)
			(end 0.120396 0.2794)
			(stroke
				(width 0.1)
				(type default)
			)
			(layer "F.Fab")
		)
		(fp_line
			(start 0.12065 -0.3048)
			(end 0.67945 -0.3048)
			(stroke
				(width 0.1)
				(type default)
			)
			(layer "F.Fab")
		)
		(fp_line
			(start 0.12065 -0.2794)
			(end 0.12065 -0.3048)
			(stroke
				(width 0.1)
				(type default)
			)
			(layer "F.Fab")
		)
		(fp_line
			(start 0.67945 -0.3048)
			(end 0.67945 0.3048)
			(stroke
				(width 0.1)
				(type default)
			)
			(layer "F.Fab")
		)
		(fp_line
			(start 0.67945 0.3048)
			(end 0.120396 0.3048)
			(stroke
				(width 0.1)
				(type default)
			)
			(layer "F.Fab")
		)
		(pad "1" smd circle
			(at -0.40005 0)
			(size 0 0)
			(layers "F.Cu" "F.Mask" "F.Paste")
			(net "OCP_SFF_P3V3_ADC_ALERT_R")
		)
		(pad "2" smd circle
			(at 0.40005 0)
			(size 0 0)
			(layers "F.Cu" "F.Mask" "F.Paste")
			(net "OCP_SFF_P3V3_P12V_ADC_R_ALERT")
		)
	)
	(footprint ""
		(layer "F.Cu")
		(at 269.85087 -351.540572 90)
		(property "Reference" "PR442"
			(at 0 0 90)
			(layer "F.SilkS")
			(hide yes)
			(effects
				(font
					(size 1.27 1.27)
				)
			)
		)
		(property "Value" ""
			(at 0 0 90)
			(layer "F.Fab")
			(effects
				(font
					(size 1.27 1.27)
				)
			)
		)
		(duplicate_pad_numbers_are_jumpers no)
		(fp_line
			(start 0.7874 -0.4064)
			(end 0.7874 0.4064)
			(stroke
				(width 0.1524)
				(type default)
			)
			(layer "F.SilkS")
		)
		(fp_line
			(start -0.7874 -0.4064)
			(end 0.7874 -0.4064)
			(stroke
				(width 0.1524)
				(type default)
			)
			(layer "F.SilkS")
		)
		(fp_line
			(start 0.7874 0.4064)
			(end -0.7874 0.4064)
			(stroke
				(width 0.1524)
				(type default)
			)
			(layer "F.SilkS")
		)
		(fp_line
			(start -0.7874 0.4064)
			(end -0.7874 -0.4064)
			(stroke
				(width 0.1524)
				(type default)
			)
			(layer "F.SilkS")
		)
		(fp_line
			(start -0.12065 -0.305054)
			(end -0.12065 -0.2794)
			(stroke
				(width 0.1)
				(type default)
			)
			(layer "F.Fab")
		)
		(fp_line
			(start -0.67945 -0.305054)
			(end -0.12065 -0.305054)
			(stroke
				(width 0.1)
				(type default)
			)
			(layer "F.Fab")
		)
		(fp_line
			(start 0.67945 -0.3048)
			(end 0.67945 0.3048)
			(stroke
				(width 0.1)
				(type default)
			)
			(layer "F.Fab")
		)
		(fp_line
			(start 0.12065 -0.3048)
			(end 0.67945 -0.3048)
			(stroke
				(width 0.1)
				(type default)
			)
			(layer "F.Fab")
		)
		(fp_line
			(start 0.12065 -0.2794)
			(end 0.12065 -0.3048)
			(stroke
				(width 0.1)
				(type default)
			)
			(layer "F.Fab")
		)
		(fp_line
			(start -0.12065 -0.2794)
			(end 0.12065 -0.2794)
			(stroke
				(width 0.1)
				(type default)
			)
			(layer "F.Fab")
		)
		(fp_line
			(start 0.120396 0.2794)
			(end -0.12065 0.2794)
			(stroke
				(width 0.1)
				(type default)
			)
			(layer "F.Fab")
		)
		(fp_line
			(start -0.12065 0.2794)
			(end -0.12065 0.3048)
			(stroke
				(width 0.1)
				(type default)
			)
			(layer "F.Fab")
		)
		(fp_line
			(start 0.67945 0.3048)
			(end 0.120396 0.3048)
			(stroke
				(width 0.1)
				(type default)
			)
			(layer "F.Fab")
		)
		(fp_line
			(start 0.120396 0.3048)
			(end 0.120396 0.2794)
			(stroke
				(width 0.1)
				(type default)
			)
			(layer "F.Fab")
		)
		(fp_line
			(start -0.12065 0.3048)
			(end -0.67945 0.3048)
			(stroke
				(width 0.1)
				(type default)
			)
			(layer "F.Fab")
		)
		(fp_line
			(start -0.67945 0.3048)
			(end -0.67945 -0.305054)
			(stroke
				(width 0.1)
				(type default)
			)
			(layer "F.Fab")
		)
		(pad "1" smd circle
			(at -0.40005 0 90)
			(size 0 0)
			(layers "F.Cu" "F.Mask" "F.Paste")
			(net "PVDDCR_CPU1_P0_PVCC")
		)
		(pad "2" smd circle
			(at 0.40005 0 90)
			(size 0 0)
			(layers "F.Cu" "F.Mask" "F.Paste")
			(net "P5V_AUX")
		)
	)
)
